FILE_TYPE = CONNECTIVITY;
{Allegro Design Entry HDL 17.2-2016 S081 (4005846) 1/11/2022}
"PAGE_NUMBER" = 18;
0"NC";
1"M_I_CPU0_SA_DQ<31:0>";
2"M_I_CPU0_SB_DQ<31:0>";
3"M_I_CPU0_SA_CB<7:0>";
4"M_I_CPU0_SB_CB<7:0>";
5"M_I_CPU0_SA_DQS_DP<9:0>";
6"M_I_CPU0_SB_DQS_DP<9:0>";
7"M_I_CPU0_SA_CA<6:0>";
8"M_I_CPU0_SB_CA<6:0>";
9"M_I_CPU0_SA_DQS_DN<9:0>";
10"M_I_CPU0_SB_DQS_DN<9:0>";
11"M_I_CPU0_ALERT_N";
12"TP_M_I_CPU0_SA_TEST39I";
13"M_I_CPU0_ALERT_R_N";
14"M_I_CPU0_CLK_DP<0>";
15"M_I_CPU0_CLK_DN<0>";
16"M_I_CPU0_SA_CS_N<0>";
17"M_I_CPU0_SA_CS_N<1>";
18"M_I_CPU0_SA_RSP<0>";
19"M_I_CPU0_SA_PAR";
20"M_I_CPU0_SB_CS_N<0>";
21"M_I_CPU0_SB_CS_N<1>";
22"M_I_CPU0_SB_RSP<0>";
23"M_I_CPU0_SB_PAR";
24"M_I_CPU0_RESET_N";
25"M_I_CPU0_SB_DQS_DN<9>";
26"M_I_CPU0_SB_DQS_DN<8>";
27"M_I_CPU0_SB_CA<6>";
28"M_I_CPU0_SA_CA<6>";
29"M_I_CPU0_SB_CA<5>";
30"M_I_CPU0_SA_CA<5>";
31"M_I_CPU0_SB_CA<4>";
32"M_I_CPU0_SA_CA<4>";
33"M_I_CPU0_SB_CA<3>";
34"M_I_CPU0_SA_CA<3>";
35"M_I_CPU0_SB_CA<2>";
36"M_I_CPU0_SA_CA<2>";
37"M_I_CPU0_SB_CA<1>";
38"M_I_CPU0_SA_CA<1>";
39"M_I_CPU0_SB_CA<0>";
40"M_I_CPU0_SA_CA<0>";
41"M_I_CPU0_SB_DQS_DP<9>";
42"M_I_CPU0_SB_DQS_DN<7>";
43"M_I_CPU0_SB_DQS_DN<6>";
44"M_I_CPU0_SB_DQS_DN<5>";
45"M_I_CPU0_SB_DQS_DN<4>";
46"M_I_CPU0_SA_DQS_DN<9>";
47"M_I_CPU0_SB_DQS_DN<3>";
48"M_I_CPU0_SB_DQS_DN<2>";
49"M_I_CPU0_SB_DQS_DN<1>";
50"M_I_CPU0_SB_DQS_DN<0>";
51"M_I_CPU0_SB_DQS_DP<8>";
52"M_I_CPU0_SB_DQS_DP<7>";
53"M_I_CPU0_SB_DQS_DP<6>";
54"M_I_CPU0_SB_DQS_DP<5>";
55"M_I_CPU0_SB_DQS_DP<4>";
56"M_I_CPU0_SA_DQS_DP<9>";
57"M_I_CPU0_SB_DQS_DP<3>";
58"M_I_CPU0_SB_DQS_DP<2>";
59"M_I_CPU0_SB_DQS_DP<1>";
60"M_I_CPU0_SB_DQS_DP<0>";
61"M_I_CPU0_SA_DQS_DN<4>";
62"M_I_CPU0_SA_DQS_DN<3>";
63"M_I_CPU0_SA_DQS_DN<2>";
64"M_I_CPU0_SA_DQS_DN<1>";
65"M_I_CPU0_SA_DQS_DN<0>";
66"M_I_CPU0_SA_DQS_DN<8>";
67"M_I_CPU0_SA_DQS_DN<7>";
68"M_I_CPU0_SA_DQS_DN<6>";
69"M_I_CPU0_SA_DQS_DN<5>";
70"M_I_CPU0_SA_DQS_DP<8>";
71"M_I_CPU0_SA_DQS_DP<7>";
72"M_I_CPU0_SA_DQS_DP<6>";
73"M_I_CPU0_SA_DQS_DP<5>";
74"M_I_CPU0_SA_DQS_DP<4>";
75"M_I_CPU0_SA_DQS_DP<0>";
76"M_I_CPU0_SA_DQS_DP<3>";
77"M_I_CPU0_SA_DQS_DP<2>";
78"M_I_CPU0_SA_DQS_DP<1>";
79"M_I_CPU0_SB_CB<2>";
80"M_I_CPU0_SA_CB<7>";
81"M_I_CPU0_SB_CB<1>";
82"M_I_CPU0_SB_CB<0>";
83"M_I_CPU0_SB_CB<7>";
84"M_I_CPU0_SB_CB<6>";
85"M_I_CPU0_SB_CB<5>";
86"M_I_CPU0_SB_CB<4>";
87"M_I_CPU0_SB_CB<3>";
88"M_I_CPU0_SB_DQ<22>";
89"M_I_CPU0_SB_DQ<21>";
90"M_I_CPU0_SA_CB<6>";
91"M_I_CPU0_SB_DQ<31>";
92"M_I_CPU0_SA_CB<5>";
93"M_I_CPU0_SB_DQ<30>";
94"M_I_CPU0_SA_CB<4>";
95"M_I_CPU0_SA_CB<3>";
96"M_I_CPU0_SA_CB<2>";
97"M_I_CPU0_SA_CB<1>";
98"M_I_CPU0_SA_CB<0>";
99"M_I_CPU0_SB_DQ<29>";
100"M_I_CPU0_SB_DQ<28>";
101"M_I_CPU0_SB_DQ<27>";
102"M_I_CPU0_SB_DQ<26>";
103"M_I_CPU0_SB_DQ<25>";
104"M_I_CPU0_SB_DQ<24>";
105"M_I_CPU0_SB_DQ<23>";
106"M_I_CPU0_SB_DQ<5>";
107"M_I_CPU0_SB_DQ<11>";
108"M_I_CPU0_SB_DQ<4>";
109"M_I_CPU0_SB_DQ<10>";
110"M_I_CPU0_SB_DQ<3>";
111"M_I_CPU0_SB_DQ<20>";
112"M_I_CPU0_SB_DQ<2>";
113"M_I_CPU0_SB_DQ<19>";
114"M_I_CPU0_SB_DQ<18>";
115"M_I_CPU0_SB_DQ<17>";
116"M_I_CPU0_SB_DQ<16>";
117"M_I_CPU0_SB_DQ<9>";
118"M_I_CPU0_SB_DQ<15>";
119"M_I_CPU0_SB_DQ<8>";
120"M_I_CPU0_SB_DQ<14>";
121"M_I_CPU0_SB_DQ<7>";
122"M_I_CPU0_SB_DQ<13>";
123"M_I_CPU0_SB_DQ<6>";
124"M_I_CPU0_SB_DQ<12>";
125"M_I_CPU0_SA_DQ<17>";
126"M_I_CPU0_SA_DQ<28>";
127"M_I_CPU0_SA_DQ<16>";
128"M_I_CPU0_SA_DQ<27>";
129"M_I_CPU0_SA_DQ<26>";
130"M_I_CPU0_SA_DQ<25>";
131"M_I_CPU0_SA_DQ<24>";
132"M_I_CPU0_SB_DQ<1>";
133"M_I_CPU0_SA_DQ<23>";
134"M_I_CPU0_SB_DQ<0>";
135"M_I_CPU0_SA_DQ<22>";
136"M_I_CPU0_SA_DQ<21>";
137"M_I_CPU0_SA_DQ<20>";
138"M_I_CPU0_SA_DQ<31>";
139"M_I_CPU0_SA_DQ<30>";
140"M_I_CPU0_SA_DQ<19>";
141"M_I_CPU0_SA_DQ<18>";
142"M_I_CPU0_SA_DQ<29>";
143"M_I_CPU0_SA_DQ<5>";
144"M_I_CPU0_SA_DQ<4>";
145"M_I_CPU0_SA_DQ<3>";
146"M_I_CPU0_SA_DQ<15>";
147"M_I_CPU0_SA_DQ<2>";
148"M_I_CPU0_SA_DQ<14>";
149"M_I_CPU0_SA_DQ<1>";
150"M_I_CPU0_SA_DQ<13>";
151"M_I_CPU0_SA_DQ<0>";
152"M_I_CPU0_SA_DQ<12>";
153"M_I_CPU0_SA_DQ<11>";
154"M_I_CPU0_SA_DQ<10>";
155"M_I_CPU0_SA_DQ<9>";
156"M_I_CPU0_SA_DQ<8>";
157"M_I_CPU0_SA_DQ<7>";
158"M_I_CPU0_SA_DQ<6>";
%"GENOA_SP5"
"9","(-4525,3600)","0","pure_quanta","I159";
;
LOCATION"U25"
$SEC"9"
CDS_SEC"9"
PART_TYPE"SMLF"
MATERIAL"IO"
VALUE"SOCKET6096_13568-001"
PART_NUMBER"DGA^6000030"
CDS_LIB"pure_quanta"
CDS_LMAN_SYM_OUTLINE"-650,2525,650,-2525"
NEEDS_NO_SIZE"TRUE";
"TEST39I"
$PN"BF21"12;
"MIA_DATA5"
$PN"K21"143;
"MIA_DATA17"
$PN"V21"125;
"MIA_DATA28"
$PN"AG19"126;
"MIA_DQS_H0"
$PN"G19"75;
"MIA_DQS_L4"
$PN"AM20"61;
"MIB_CHECK2"
$PN"CA19"79;
"MIB_DATA5"
$PN"CG21"106;
"MIB_DATA11"
$PN"CK21"107;
"MIB_DATA22"
$PN"CW19"88;
"MI_ALERT_L"
$PN"AT21"13;
"MIA0_RSP_L"
$PN"BN21"18;
"MIA1_RSP_L"
$PN"BP21"0;
"MIA_CHECK7"
$PN"AR21"80;
"MIA_DATA4"
$PN"J19"144;
"MIA_DATA16"
$PN"U19"127;
"MIA_DATA27"
$PN"AE21"128;
"MIA_DQS_L3"
$PN"AF20"62;
"MIB_CHECK1"
$PN"CA21"81;
"MIB_DATA4"
$PN"CF20"108;
"MIB_DATA10"
$PN"CJ19"109;
"MIB_DATA21"
$PN"CW21"89;
"MIB_PAR"
$PN"BL21"23;
"MIA_CHECK6"
$PN"AP20"90;
"MIA_DATA3"
$PN"G21"145;
"MIA_DATA15"
$PN"U21"146;
"MIA_DATA26"
$PN"AD20"129;
"MIA_DQS_L2"
$PN"Y20"63;
"MIA_PAR"
$PN"BC21"19;
"MIB1_CS_L1"
$PN"BM20"0;
"MIB_CHECK0"
$PN"BY20"82;
"MIB_DATA3"
$PN"CD21"110;
"MIB_DATA20"
$PN"CV20"111;
"MIB_DATA31"
$PN"DF21"91;
"MIB_DQS_H9"
$PN"BV20"41;
"MIA_CHECK5"
$PN"AP21"92;
"MIA_DATA2"
$PN"F20"147;
"MIA_DATA14"
$PN"T20"148;
"MIA_DATA25"
$PN"AD21"130;
"MIA_DQS_L1"
$PN"P20"64;
"MIB0_CS_L1"
$PN"BN19"21;
"MIB1_CS_L0"
$PN"BL19"0;
"MIB_DATA2"
$PN"CC19"112;
"MIB_DATA30"
$PN"DE19"93;
"MIB_DQS_H8"
$PN"DD21"51;
"MIA_CHECK4"
$PN"AN19"94;
"MIA_DATA1"
$PN"F21"149;
"MIA_DATA13"
$PN"T21"150;
"MIA_DATA24"
$PN"AC19"131;
"MIA_DQS_L0"
$PN"H20"65;
"MIB0_CS_L0"
$PN"BM21"20;
"MIB_DATA1"
$PN"CC21"132;
"MIB_DQS_H7"
$PN"CV21"52;
"MIA_CHECK3"
$PN"AL21"95;
"MIA_DATA0"
$PN"E19"151;
"MIA_DATA12"
$PN"R19"152;
"MIA_DATA23"
$PN"AC21"133;
"MIB_DATA0"
$PN"CB20"134;
"MIB_DQS_H6"
$PN"CM21"53;
"MI_RESET_L"
$PN"AU21"24;
"MI0_CLK_L"
$PN"BD20"15;
"MI1_CLK_L"
$PN"BG19"0;
"MIA_CHECK2"
$PN"AK20"96;
"MIA_DATA11"
$PN"N21"153;
"MIA_DATA22"
$PN"AB20"135;
"MIB_DQS_H5"
$PN"CF21"54;
"MIB_DQS_L9"
$PN"BW19"25;
"MIA_CHECK1"
$PN"AK21"97;
"MIA_DATA10"
$PN"M20"154;
"MIA_DATA21"
$PN"AB21"136;
"MIB_DQS_H4"
$PN"BY21"55;
"MIB_DQS_L8"
$PN"DC21"26;
"MIA_CHECK0"
$PN"AJ19"98;
"MIA_DATA20"
$PN"AA19"137;
"MIA_DATA31"
$PN"AJ21"138;
"MIA_DQS_H9"
$PN"AN21"56;
"MIB_CA6"
$PN"BK20"27;
"MIB_DQS_H3"
$PN"DB20"57;
"MIB_DQS_L7"
$PN"CU21"42;
"MIA0_CS_L1"
$PN"AV21"17;
"MIA1_CS_L1"
$PN"AW21"0;
"MIA_CA6"
$PN"BB21"28;
"MIA_DATA30"
$PN"AH20"139;
"MIA_DQS_H8"
$PN"AG21"70;
"MIB_CA5"
$PN"BK21"29;
"MIB_DATA19"
$PN"CT21"113;
"MIB_DQS_H2"
$PN"CT20"58;
"MIB_DQS_L6"
$PN"CL21"43;
"MI0_CLK_H"
$PN"BC19"14;
"MI1_CLK_H"
$PN"BF20"0;
"MIA0_CS_L0"
$PN"AU19"16;
"MIA1_CS_L0"
$PN"AV20"0;
"MIA_CA5"
$PN"BB20"30;
"MIA_DQS_H7"
$PN"AA21"71;
"MIB_CA4"
$PN"BJ21"31;
"MIB_DATA18"
$PN"CR19"114;
"MIB_DATA29"
$PN"DE21"99;
"MIB_DQS_H1"
$PN"CK20"59;
"MIB_DQS_L5"
$PN"CE21"44;
"MIA_CA4"
$PN"BA19"32;
"MIA_DQS_H6"
$PN"R21"72;
"MIB1_RSP_L"
$PN"BR19"0;
"MIB_CA3"
$PN"BJ19"33;
"MIB_DATA17"
$PN"CR21"115;
"MIB_DATA28"
$PN"DD20"100;
"MIB_DQS_H0"
$PN"CD20"60;
"MIB_DQS_L4"
$PN"BW21"45;
"MIA_CA3"
$PN"BA21"34;
"MIA_DQS_H5"
$PN"J21"73;
"MIA_DQS_L9"
$PN"AM21"46;
"MIB0_RSP_L"
$PN"BP20"22;
"MIB_CA2"
$PN"BH20"35;
"MIB_CHECK7"
$PN"BV21"83;
"MIB_DATA16"
$PN"CP20"116;
"MIB_DATA27"
$PN"DB21"101;
"MIB_DQS_L3"
$PN"DC19"47;
"MIA_CA2"
$PN"AY21"36;
"MIA_DATA9"
$PN"M21"155;
"MIA_DQS_H4"
$PN"AL19"74;
"MIA_DQS_L8"
$PN"AF21"66;
"MIB_CA1"
$PN"BH21"37;
"MIB_CHECK6"
$PN"BU19"84;
"MIB_DATA9"
$PN"CJ21"117;
"MIB_DATA15"
$PN"CP21"118;
"MIB_DATA26"
$PN"DA19"102;
"MIB_DQS_L2"
$PN"CU19"48;
"MIA_CA1"
$PN"AY20"38;
"MIA_DATA8"
$PN"L19"156;
"MIA_DQS_H3"
$PN"AE19"76;
"MIA_DQS_L7"
$PN"Y21"67;
"MIB_CA0"
$PN"BG21"39;
"MIB_CHECK5"
$PN"BU21"85;
"MIB_DATA8"
$PN"CH20"119;
"MIB_DATA14"
$PN"CN19"120;
"MIB_DATA25"
$PN"DA21"103;
"MIB_DQS_L1"
$PN"CL19"49;
"MIA_CA0"
$PN"AW19"40;
"MIA_DATA7"
$PN"L21"157;
"MIA_DATA19"
$PN"W21"140;
"MIA_DQS_H2"
$PN"W19"77;
"MIA_DQS_L6"
$PN"P21"68;
"MIB_CHECK4"
$PN"BT20"86;
"MIB_DATA7"
$PN"CH21"121;
"MIB_DATA13"
$PN"CN21"122;
"MIB_DATA24"
$PN"CY20"104;
"MIB_DQS_L0"
$PN"CE19"50;
"MIA_DATA6"
$PN"K20"158;
"MIA_DATA18"
$PN"V20"141;
"MIA_DATA29"
$PN"AH21"142;
"MIA_DQS_H1"
$PN"N19"78;
"MIA_DQS_L5"
$PN"H21"69;
"MIB_CHECK3"
$PN"CB21"87;
"MIB_DATA6"
$PN"CG19"123;
"MIB_DATA12"
$PN"CM20"124;
"MIB_DATA23"
$PN"CY21"105;
%"TAP"
"1","(-3250,5975)","0","mstr_standard","I162";
;
CDS_LIB"mstr_standard"
BODY_TYPE"PLUMBING"
HDL_TAP"TRUE";
"B \NAC \NWC"1;
"S \NAC"
BN"0"151;
%"TAP"
"1","(-3250,5925)","0","mstr_standard","I163";
;
CDS_LIB"mstr_standard"
BODY_TYPE"PLUMBING"
HDL_TAP"TRUE";
"B \NAC \NWC"1;
"S \NAC"
BN"1"149;
%"TAP"
"1","(-3250,5775)","0","mstr_standard","I164";
;
CDS_LIB"mstr_standard"
BODY_TYPE"PLUMBING"
HDL_TAP"TRUE";
"B \NAC \NWC"1;
"S \NAC"
BN"4"144;
%"TAP"
"1","(-3250,5825)","0","mstr_standard","I165";
;
CDS_LIB"mstr_standard"
BODY_TYPE"PLUMBING"
HDL_TAP"TRUE";
"B \NAC \NWC"1;
"S \NAC"
BN"3"145;
%"TAP"
"1","(-3250,5875)","0","mstr_standard","I166";
;
CDS_LIB"mstr_standard"
BODY_TYPE"PLUMBING"
HDL_TAP"TRUE";
"B \NAC \NWC"1;
"S \NAC"
BN"2"147;
%"TAP"
"1","(-3250,5675)","0","mstr_standard","I167";
;
CDS_LIB"mstr_standard"
BODY_TYPE"PLUMBING"
HDL_TAP"TRUE";
"B \NAC \NWC"1;
"S \NAC"
BN"6"158;
%"TAP"
"1","(-3250,5725)","0","mstr_standard","I168";
;
CDS_LIB"mstr_standard"
BODY_TYPE"PLUMBING"
HDL_TAP"TRUE";
"B \NAC \NWC"1;
"S \NAC"
BN"5"143;
%"TAP"
"1","(-3250,5525)","0","mstr_standard","I169";
;
CDS_LIB"mstr_standard"
BODY_TYPE"PLUMBING"
HDL_TAP"TRUE";
"B \NAC \NWC"1;
"S \NAC"
BN"8"156;
%"TAP"
"1","(-3250,5625)","0","mstr_standard","I170";
;
CDS_LIB"mstr_standard"
BODY_TYPE"PLUMBING"
HDL_TAP"TRUE";
"B \NAC \NWC"1;
"S \NAC"
BN"7"157;
%"TAP"
"1","(-3250,5425)","0","mstr_standard","I171";
;
CDS_LIB"mstr_standard"
BODY_TYPE"PLUMBING"
HDL_TAP"TRUE";
"B \NAC \NWC"1;
"S \NAC"
BN"10"154;
%"TAP"
"1","(-3250,5475)","0","mstr_standard","I172";
;
CDS_LIB"mstr_standard"
BODY_TYPE"PLUMBING"
HDL_TAP"TRUE";
"B \NAC \NWC"1;
"S \NAC"
BN"9"155;
%"TAP"
"1","(-3250,5275)","0","mstr_standard","I173";
;
CDS_LIB"mstr_standard"
BODY_TYPE"PLUMBING"
HDL_TAP"TRUE";
"B \NAC \NWC"1;
"S \NAC"
BN"13"150;
%"TAP"
"1","(-3250,5325)","0","mstr_standard","I174";
;
CDS_LIB"mstr_standard"
BODY_TYPE"PLUMBING"
HDL_TAP"TRUE";
"B \NAC \NWC"1;
"S \NAC"
BN"12"152;
%"TAP"
"1","(-3250,5375)","0","mstr_standard","I175";
;
CDS_LIB"mstr_standard"
BODY_TYPE"PLUMBING"
HDL_TAP"TRUE";
"B \NAC \NWC"1;
"S \NAC"
BN"11"153;
%"TAP"
"1","(-3250,5225)","0","mstr_standard","I176";
;
CDS_LIB"mstr_standard"
BODY_TYPE"PLUMBING"
HDL_TAP"TRUE";
"B \NAC \NWC"1;
"S \NAC"
BN"14"148;
%"TAP"
"1","(-3250,5175)","0","mstr_standard","I177";
;
CDS_LIB"mstr_standard"
BODY_TYPE"PLUMBING"
HDL_TAP"TRUE";
"B \NAC \NWC"1;
"S \NAC"
BN"15"146;
%"TAP"
"1","(-3250,5075)","0","mstr_standard","I178";
;
CDS_LIB"mstr_standard"
BODY_TYPE"PLUMBING"
HDL_TAP"TRUE";
"B \NAC \NWC"1;
"S \NAC"
BN"16"127;
%"TAP"
"1","(-3250,5025)","0","mstr_standard","I179";
;
CDS_LIB"mstr_standard"
BODY_TYPE"PLUMBING"
HDL_TAP"TRUE";
"B \NAC \NWC"1;
"S \NAC"
BN"17"125;
%"TAP"
"1","(-3250,4875)","0","mstr_standard","I180";
;
CDS_LIB"mstr_standard"
BODY_TYPE"PLUMBING"
HDL_TAP"TRUE";
"B \NAC \NWC"1;
"S \NAC"
BN"20"137;
%"TAP"
"1","(-3250,4925)","0","mstr_standard","I181";
;
CDS_LIB"mstr_standard"
BODY_TYPE"PLUMBING"
HDL_TAP"TRUE";
"B \NAC \NWC"1;
"S \NAC"
BN"19"140;
%"TAP"
"1","(-3250,4975)","0","mstr_standard","I182";
;
CDS_LIB"mstr_standard"
BODY_TYPE"PLUMBING"
HDL_TAP"TRUE";
"B \NAC \NWC"1;
"S \NAC"
BN"18"141;
%"TAP"
"1","(-3250,4775)","0","mstr_standard","I183";
;
CDS_LIB"mstr_standard"
BODY_TYPE"PLUMBING"
HDL_TAP"TRUE";
"B \NAC \NWC"1;
"S \NAC"
BN"22"135;
%"TAP"
"1","(-3250,4825)","0","mstr_standard","I184";
;
CDS_LIB"mstr_standard"
BODY_TYPE"PLUMBING"
HDL_TAP"TRUE";
"B \NAC \NWC"1;
"S \NAC"
BN"21"136;
%"TAP"
"1","(-3250,4725)","0","mstr_standard","I185";
;
CDS_LIB"mstr_standard"
BODY_TYPE"PLUMBING"
HDL_TAP"TRUE";
"B \NAC \NWC"1;
"S \NAC"
BN"23"133;
%"TAP"
"1","(-3250,4625)","0","mstr_standard","I186";
;
CDS_LIB"mstr_standard"
BODY_TYPE"PLUMBING"
HDL_TAP"TRUE";
"B \NAC \NWC"1;
"S \NAC"
BN"24"131;
%"TAP"
"1","(-3250,4525)","0","mstr_standard","I187";
;
CDS_LIB"mstr_standard"
BODY_TYPE"PLUMBING"
HDL_TAP"TRUE";
"B \NAC \NWC"1;
"S \NAC"
BN"26"129;
%"TAP"
"1","(-3250,4575)","0","mstr_standard","I188";
;
CDS_LIB"mstr_standard"
BODY_TYPE"PLUMBING"
HDL_TAP"TRUE";
"B \NAC \NWC"1;
"S \NAC"
BN"25"130;
%"TAP"
"1","(-3250,4375)","0","mstr_standard","I189";
;
CDS_LIB"mstr_standard"
BODY_TYPE"PLUMBING"
HDL_TAP"TRUE";
"B \NAC \NWC"1;
"S \NAC"
BN"29"142;
%"TAP"
"1","(-3250,4425)","0","mstr_standard","I190";
;
CDS_LIB"mstr_standard"
BODY_TYPE"PLUMBING"
HDL_TAP"TRUE";
"B \NAC \NWC"1;
"S \NAC"
BN"28"126;
%"TAP"
"1","(-3250,4475)","0","mstr_standard","I191";
;
CDS_LIB"mstr_standard"
BODY_TYPE"PLUMBING"
HDL_TAP"TRUE";
"B \NAC \NWC"1;
"S \NAC"
BN"27"128;
%"TAP"
"1","(-3250,4325)","0","mstr_standard","I192";
;
CDS_LIB"mstr_standard"
BODY_TYPE"PLUMBING"
HDL_TAP"TRUE";
"B \NAC \NWC"1;
"S \NAC"
BN"30"139;
%"TAP"
"1","(-3250,4275)","0","mstr_standard","I193";
;
CDS_LIB"mstr_standard"
BODY_TYPE"PLUMBING"
HDL_TAP"TRUE";
"B \NAC \NWC"1;
"S \NAC"
BN"31"138;
%"TAP"
"1","(-3250,4175)","0","mstr_standard","I194";
;
CDS_LIB"mstr_standard"
BODY_TYPE"PLUMBING"
HDL_TAP"TRUE";
"B \NAC \NWC"2;
"S \NAC"
BN"0"134;
%"TAP"
"1","(-3250,4125)","0","mstr_standard","I195";
;
CDS_LIB"mstr_standard"
BODY_TYPE"PLUMBING"
HDL_TAP"TRUE";
"B \NAC \NWC"2;
"S \NAC"
BN"1"132;
%"TAP"
"1","(-3250,3975)","0","mstr_standard","I197";
;
CDS_LIB"mstr_standard"
BODY_TYPE"PLUMBING"
HDL_TAP"TRUE";
"B \NAC \NWC"2;
"S \NAC"
BN"4"108;
%"TAP"
"1","(-3250,4075)","0","mstr_standard","I198";
;
CDS_LIB"mstr_standard"
BODY_TYPE"PLUMBING"
HDL_TAP"TRUE";
"B \NAC \NWC"2;
"S \NAC"
BN"2"112;
%"TAP"
"1","(-3250,4025)","0","mstr_standard","I199";
;
CDS_LIB"mstr_standard"
BODY_TYPE"PLUMBING"
HDL_TAP"TRUE";
"B \NAC \NWC"2;
"S \NAC"
BN"3"110;
%"TAP"
"1","(-3250,3925)","0","mstr_standard","I200";
;
CDS_LIB"mstr_standard"
BODY_TYPE"PLUMBING"
HDL_TAP"TRUE";
"B \NAC \NWC"2;
"S \NAC"
BN"5"106;
%"TAP"
"1","(-3250,3875)","0","mstr_standard","I201";
;
CDS_LIB"mstr_standard"
BODY_TYPE"PLUMBING"
HDL_TAP"TRUE";
"B \NAC \NWC"2;
"S \NAC"
BN"6"123;
%"TAP"
"1","(-3250,3825)","0","mstr_standard","I202";
;
CDS_LIB"mstr_standard"
BODY_TYPE"PLUMBING"
HDL_TAP"TRUE";
"B \NAC \NWC"2;
"S \NAC"
BN"7"121;
%"TAP"
"1","(-3250,3725)","0","mstr_standard","I203";
;
CDS_LIB"mstr_standard"
BODY_TYPE"PLUMBING"
HDL_TAP"TRUE";
"B \NAC \NWC"2;
"S \NAC"
BN"8"119;
%"TAP"
"1","(-3250,3675)","0","mstr_standard","I204";
;
CDS_LIB"mstr_standard"
BODY_TYPE"PLUMBING"
HDL_TAP"TRUE";
"B \NAC \NWC"2;
"S \NAC"
BN"9"117;
%"TAP"
"1","(-3250,3625)","0","mstr_standard","I205";
;
CDS_LIB"mstr_standard"
BODY_TYPE"PLUMBING"
HDL_TAP"TRUE";
"B \NAC \NWC"2;
"S \NAC"
BN"10"109;
%"TAP"
"1","(-3250,3575)","0","mstr_standard","I206";
;
CDS_LIB"mstr_standard"
BODY_TYPE"PLUMBING"
HDL_TAP"TRUE";
"B \NAC \NWC"2;
"S \NAC"
BN"11"107;
%"TAP"
"1","(-3250,3525)","0","mstr_standard","I207";
;
CDS_LIB"mstr_standard"
BODY_TYPE"PLUMBING"
HDL_TAP"TRUE";
"B \NAC \NWC"2;
"S \NAC"
BN"12"124;
%"TAP"
"1","(-3250,3475)","0","mstr_standard","I208";
;
CDS_LIB"mstr_standard"
BODY_TYPE"PLUMBING"
HDL_TAP"TRUE";
"B \NAC \NWC"2;
"S \NAC"
BN"13"122;
%"TAP"
"1","(-3250,3375)","0","mstr_standard","I209";
;
CDS_LIB"mstr_standard"
BODY_TYPE"PLUMBING"
HDL_TAP"TRUE";
"B \NAC \NWC"2;
"S \NAC"
BN"15"118;
%"TAP"
"1","(-3250,3425)","0","mstr_standard","I210";
;
CDS_LIB"mstr_standard"
BODY_TYPE"PLUMBING"
HDL_TAP"TRUE";
"B \NAC \NWC"2;
"S \NAC"
BN"14"120;
%"TAP"
"1","(-3250,3275)","0","mstr_standard","I211";
;
CDS_LIB"mstr_standard"
BODY_TYPE"PLUMBING"
HDL_TAP"TRUE";
"B \NAC \NWC"2;
"S \NAC"
BN"16"116;
%"TAP"
"1","(-3250,3225)","0","mstr_standard","I212";
;
CDS_LIB"mstr_standard"
BODY_TYPE"PLUMBING"
HDL_TAP"TRUE";
"B \NAC \NWC"2;
"S \NAC"
BN"17"115;
%"TAP"
"1","(-3250,3175)","0","mstr_standard","I213";
;
CDS_LIB"mstr_standard"
BODY_TYPE"PLUMBING"
HDL_TAP"TRUE";
"B \NAC \NWC"2;
"S \NAC"
BN"18"114;
%"TAP"
"1","(-3250,3125)","0","mstr_standard","I214";
;
CDS_LIB"mstr_standard"
BODY_TYPE"PLUMBING"
HDL_TAP"TRUE";
"B \NAC \NWC"2;
"S \NAC"
BN"19"113;
%"TAP"
"1","(-3250,3075)","0","mstr_standard","I215";
;
CDS_LIB"mstr_standard"
BODY_TYPE"PLUMBING"
HDL_TAP"TRUE";
"B \NAC \NWC"2;
"S \NAC"
BN"20"111;
%"TAP"
"1","(-3250,2975)","0","mstr_standard","I216";
;
CDS_LIB"mstr_standard"
BODY_TYPE"PLUMBING"
HDL_TAP"TRUE";
"B \NAC \NWC"2;
"S \NAC"
BN"22"88;
%"TAP"
"1","(-3250,3025)","0","mstr_standard","I217";
;
CDS_LIB"mstr_standard"
BODY_TYPE"PLUMBING"
HDL_TAP"TRUE";
"B \NAC \NWC"2;
"S \NAC"
BN"21"89;
%"TAP"
"1","(-3250,2925)","0","mstr_standard","I218";
;
CDS_LIB"mstr_standard"
BODY_TYPE"PLUMBING"
HDL_TAP"TRUE";
"B \NAC \NWC"2;
"S \NAC"
BN"23"105;
%"TAP"
"1","(-3250,2825)","0","mstr_standard","I219";
;
CDS_LIB"mstr_standard"
BODY_TYPE"PLUMBING"
HDL_TAP"TRUE";
"B \NAC \NWC"2;
"S \NAC"
BN"24"104;
%"TAP"
"1","(-3250,2775)","0","mstr_standard","I220";
;
CDS_LIB"mstr_standard"
BODY_TYPE"PLUMBING"
HDL_TAP"TRUE";
"B \NAC \NWC"2;
"S \NAC"
BN"25"103;
%"TAP"
"1","(-3250,2725)","0","mstr_standard","I221";
;
CDS_LIB"mstr_standard"
BODY_TYPE"PLUMBING"
HDL_TAP"TRUE";
"B \NAC \NWC"2;
"S \NAC"
BN"26"102;
%"TAP"
"1","(-3250,2575)","0","mstr_standard","I222";
;
CDS_LIB"mstr_standard"
BODY_TYPE"PLUMBING"
HDL_TAP"TRUE";
"B \NAC \NWC"2;
"S \NAC"
BN"29"99;
%"TAP"
"1","(-3250,2625)","0","mstr_standard","I223";
;
CDS_LIB"mstr_standard"
BODY_TYPE"PLUMBING"
HDL_TAP"TRUE";
"B \NAC \NWC"2;
"S \NAC"
BN"28"100;
%"TAP"
"1","(-3250,2675)","0","mstr_standard","I224";
;
CDS_LIB"mstr_standard"
BODY_TYPE"PLUMBING"
HDL_TAP"TRUE";
"B \NAC \NWC"2;
"S \NAC"
BN"27"101;
%"TAP"
"1","(-3250,2525)","0","mstr_standard","I225";
;
CDS_LIB"mstr_standard"
BODY_TYPE"PLUMBING"
HDL_TAP"TRUE";
"B \NAC \NWC"2;
"S \NAC"
BN"30"93;
%"TAP"
"1","(-3250,2475)","0","mstr_standard","I226";
;
CDS_LIB"mstr_standard"
BODY_TYPE"PLUMBING"
HDL_TAP"TRUE";
"B \NAC \NWC"2;
"S \NAC"
BN"31"91;
%"TAP"
"1","(-3250,2325)","0","mstr_standard","I227";
;
CDS_LIB"mstr_standard"
BODY_TYPE"PLUMBING"
HDL_TAP"TRUE";
"B \NAC \NWC"3;
"S \NAC"
BN"1"97;
%"TAP"
"1","(-3250,2375)","0","mstr_standard","I228";
;
CDS_LIB"mstr_standard"
BODY_TYPE"PLUMBING"
HDL_TAP"TRUE";
"B \NAC \NWC"3;
"S \NAC"
BN"0"98;
%"TAP"
"1","(-3250,2225)","0","mstr_standard","I229";
;
CDS_LIB"mstr_standard"
BODY_TYPE"PLUMBING"
HDL_TAP"TRUE";
"B \NAC \NWC"3;
"S \NAC"
BN"3"95;
%"TAP"
"1","(-3250,2275)","0","mstr_standard","I230";
;
CDS_LIB"mstr_standard"
BODY_TYPE"PLUMBING"
HDL_TAP"TRUE";
"B \NAC \NWC"3;
"S \NAC"
BN"2"96;
%"TAP"
"1","(-3250,2075)","0","mstr_standard","I231";
;
CDS_LIB"mstr_standard"
BODY_TYPE"PLUMBING"
HDL_TAP"TRUE";
"B \NAC \NWC"3;
"S \NAC"
BN"6"90;
%"TAP"
"1","(-3250,2125)","0","mstr_standard","I232";
;
CDS_LIB"mstr_standard"
BODY_TYPE"PLUMBING"
HDL_TAP"TRUE";
"B \NAC \NWC"3;
"S \NAC"
BN"5"92;
%"TAP"
"1","(-3250,2175)","0","mstr_standard","I233";
;
CDS_LIB"mstr_standard"
BODY_TYPE"PLUMBING"
HDL_TAP"TRUE";
"B \NAC \NWC"3;
"S \NAC"
BN"4"94;
%"TAP"
"1","(-3250,1925)","0","mstr_standard","I235";
;
CDS_LIB"mstr_standard"
BODY_TYPE"PLUMBING"
HDL_TAP"TRUE";
"B \NAC \NWC"4;
"S \NAC"
BN"0"82;
%"TAP"
"1","(-3250,2025)","0","mstr_standard","I236";
;
CDS_LIB"mstr_standard"
BODY_TYPE"PLUMBING"
HDL_TAP"TRUE";
"B \NAC \NWC"3;
"S \NAC"
BN"7"80;
%"TAP"
"1","(-3250,1825)","0","mstr_standard","I237";
;
CDS_LIB"mstr_standard"
BODY_TYPE"PLUMBING"
HDL_TAP"TRUE";
"B \NAC \NWC"4;
"S \NAC"
BN"2"79;
%"TAP"
"1","(-3250,1875)","0","mstr_standard","I238";
;
CDS_LIB"mstr_standard"
BODY_TYPE"PLUMBING"
HDL_TAP"TRUE";
"B \NAC \NWC"4;
"S \NAC"
BN"1"81;
%"TAP"
"1","(-3250,1775)","0","mstr_standard","I239";
;
CDS_LIB"mstr_standard"
BODY_TYPE"PLUMBING"
HDL_TAP"TRUE";
"B \NAC \NWC"4;
"S \NAC"
BN"3"87;
%"TAP"
"1","(-3250,1725)","0","mstr_standard","I240";
;
CDS_LIB"mstr_standard"
BODY_TYPE"PLUMBING"
HDL_TAP"TRUE";
"B \NAC \NWC"4;
"S \NAC"
BN"4"86;
%"TAP"
"1","(-3250,1675)","0","mstr_standard","I241";
;
CDS_LIB"mstr_standard"
BODY_TYPE"PLUMBING"
HDL_TAP"TRUE";
"B \NAC \NWC"4;
"S \NAC"
BN"5"85;
%"TAP"
"1","(-3250,1575)","0","mstr_standard","I242";
;
CDS_LIB"mstr_standard"
BODY_TYPE"PLUMBING"
HDL_TAP"TRUE";
"B \NAC \NWC"4;
"S \NAC"
BN"7"83;
%"TAP"
"1","(-3250,1625)","0","mstr_standard","I243";
;
CDS_LIB"mstr_standard"
BODY_TYPE"PLUMBING"
HDL_TAP"TRUE";
"B \NAC \NWC"4;
"S \NAC"
BN"6"84;
%"TAP"
"1","(-5675,5975)","2","mstr_standard","I244";
;
CDS_LIB"mstr_standard"
BODY_TYPE"PLUMBING"
HDL_TAP"TRUE";
"B \NAC \NWC"5;
"S \NAC"
BN"0"75;
%"TAP"
"1","(-5675,5875)","2","mstr_standard","I245";
;
CDS_LIB"mstr_standard"
BODY_TYPE"PLUMBING"
HDL_TAP"TRUE";
"B \NAC \NWC"5;
"S \NAC"
BN"1"78;
%"TAP"
"1","(-5675,5775)","2","mstr_standard","I246";
;
CDS_LIB"mstr_standard"
BODY_TYPE"PLUMBING"
HDL_TAP"TRUE";
"B \NAC \NWC"5;
"S \NAC"
BN"2"77;
%"TAP"
"1","(-5675,5675)","2","mstr_standard","I247";
;
CDS_LIB"mstr_standard"
BODY_TYPE"PLUMBING"
HDL_TAP"TRUE";
"B \NAC \NWC"5;
"S \NAC"
BN"3"76;
%"TAP"
"1","(-5675,5575)","2","mstr_standard","I248";
;
CDS_LIB"mstr_standard"
BODY_TYPE"PLUMBING"
HDL_TAP"TRUE";
"B \NAC \NWC"5;
"S \NAC"
BN"4"74;
%"TAP"
"1","(-5675,5475)","2","mstr_standard","I249";
;
CDS_LIB"mstr_standard"
BODY_TYPE"PLUMBING"
HDL_TAP"TRUE";
"B \NAC \NWC"5;
"S \NAC"
BN"5"73;
%"TAP"
"1","(-5675,5375)","2","mstr_standard","I250";
;
CDS_LIB"mstr_standard"
BODY_TYPE"PLUMBING"
HDL_TAP"TRUE";
"B \NAC \NWC"5;
"S \NAC"
BN"6"72;
%"TAP"
"1","(-5675,5275)","2","mstr_standard","I251";
;
CDS_LIB"mstr_standard"
BODY_TYPE"PLUMBING"
HDL_TAP"TRUE";
"B \NAC \NWC"5;
"S \NAC"
BN"7"71;
%"TAP"
"1","(-5675,5175)","2","mstr_standard","I252";
;
CDS_LIB"mstr_standard"
BODY_TYPE"PLUMBING"
HDL_TAP"TRUE";
"B \NAC \NWC"5;
"S \NAC"
BN"8"70;
%"TAP"
"1","(-5875,5925)","2","mstr_standard","I253";
;
CDS_LIB"mstr_standard"
BODY_TYPE"PLUMBING"
HDL_TAP"TRUE";
"B \NAC \NWC"9;
"S \NAC"
BN"0"65;
%"TAP"
"1","(-5875,5825)","2","mstr_standard","I254";
;
CDS_LIB"mstr_standard"
BODY_TYPE"PLUMBING"
HDL_TAP"TRUE";
"B \NAC \NWC"9;
"S \NAC"
BN"1"64;
%"TAP"
"1","(-5875,5725)","2","mstr_standard","I255";
;
CDS_LIB"mstr_standard"
BODY_TYPE"PLUMBING"
HDL_TAP"TRUE";
"B \NAC \NWC"9;
"S \NAC"
BN"2"63;
%"TAP"
"1","(-5875,5525)","2","mstr_standard","I256";
;
CDS_LIB"mstr_standard"
BODY_TYPE"PLUMBING"
HDL_TAP"TRUE";
"B \NAC \NWC"9;
"S \NAC"
BN"4"61;
%"TAP"
"1","(-5875,5625)","2","mstr_standard","I257";
;
CDS_LIB"mstr_standard"
BODY_TYPE"PLUMBING"
HDL_TAP"TRUE";
"B \NAC \NWC"9;
"S \NAC"
BN"3"62;
%"TAP"
"1","(-5875,5425)","2","mstr_standard","I258";
;
CDS_LIB"mstr_standard"
BODY_TYPE"PLUMBING"
HDL_TAP"TRUE";
"B \NAC \NWC"9;
"S \NAC"
BN"5"69;
%"TAP"
"1","(-5875,5325)","2","mstr_standard","I259";
;
CDS_LIB"mstr_standard"
BODY_TYPE"PLUMBING"
HDL_TAP"TRUE";
"B \NAC \NWC"9;
"S \NAC"
BN"6"68;
%"TAP"
"1","(-5875,5225)","2","mstr_standard","I260";
;
CDS_LIB"mstr_standard"
BODY_TYPE"PLUMBING"
HDL_TAP"TRUE";
"B \NAC \NWC"9;
"S \NAC"
BN"7"67;
%"TAP"
"1","(-5875,5125)","2","mstr_standard","I261";
;
CDS_LIB"mstr_standard"
BODY_TYPE"PLUMBING"
HDL_TAP"TRUE";
"B \NAC \NWC"9;
"S \NAC"
BN"8"66;
%"TAP"
"1","(-5675,5075)","2","mstr_standard","I262";
;
CDS_LIB"mstr_standard"
BODY_TYPE"PLUMBING"
HDL_TAP"TRUE";
"B \NAC \NWC"5;
"S \NAC"
BN"9"56;
%"TAP"
"1","(-5675,4925)","2","mstr_standard","I263";
;
CDS_LIB"mstr_standard"
BODY_TYPE"PLUMBING"
HDL_TAP"TRUE";
"B \NAC \NWC"6;
"S \NAC"
BN"0"60;
%"TAP"
"1","(-5675,4825)","2","mstr_standard","I264";
;
CDS_LIB"mstr_standard"
BODY_TYPE"PLUMBING"
HDL_TAP"TRUE";
"B \NAC \NWC"6;
"S \NAC"
BN"1"59;
%"TAP"
"1","(-5675,4725)","2","mstr_standard","I265";
;
CDS_LIB"mstr_standard"
BODY_TYPE"PLUMBING"
HDL_TAP"TRUE";
"B \NAC \NWC"6;
"S \NAC"
BN"2"58;
%"TAP"
"1","(-5675,4625)","2","mstr_standard","I266";
;
CDS_LIB"mstr_standard"
BODY_TYPE"PLUMBING"
HDL_TAP"TRUE";
"B \NAC \NWC"6;
"S \NAC"
BN"3"57;
%"TAP"
"1","(-5675,4525)","2","mstr_standard","I267";
;
CDS_LIB"mstr_standard"
BODY_TYPE"PLUMBING"
HDL_TAP"TRUE";
"B \NAC \NWC"6;
"S \NAC"
BN"4"55;
%"TAP"
"1","(-5675,4425)","2","mstr_standard","I268";
;
CDS_LIB"mstr_standard"
BODY_TYPE"PLUMBING"
HDL_TAP"TRUE";
"B \NAC \NWC"6;
"S \NAC"
BN"5"54;
%"TAP"
"1","(-5675,4325)","2","mstr_standard","I269";
;
CDS_LIB"mstr_standard"
BODY_TYPE"PLUMBING"
HDL_TAP"TRUE";
"B \NAC \NWC"6;
"S \NAC"
BN"6"53;
%"TAP"
"1","(-5675,4225)","2","mstr_standard","I270";
;
CDS_LIB"mstr_standard"
BODY_TYPE"PLUMBING"
HDL_TAP"TRUE";
"B \NAC \NWC"6;
"S \NAC"
BN"7"52;
%"TAP"
"1","(-5675,4125)","2","mstr_standard","I271";
;
CDS_LIB"mstr_standard"
BODY_TYPE"PLUMBING"
HDL_TAP"TRUE";
"B \NAC \NWC"6;
"S \NAC"
BN"8"51;
%"TAP"
"1","(-5875,4875)","2","mstr_standard","I272";
;
CDS_LIB"mstr_standard"
BODY_TYPE"PLUMBING"
HDL_TAP"TRUE";
"B \NAC \NWC"10;
"S \NAC"
BN"0"50;
%"TAP"
"1","(-5875,5025)","2","mstr_standard","I273";
;
CDS_LIB"mstr_standard"
BODY_TYPE"PLUMBING"
HDL_TAP"TRUE";
"B \NAC \NWC"9;
"S \NAC"
BN"9"46;
%"TAP"
"1","(-5875,4775)","2","mstr_standard","I274";
;
CDS_LIB"mstr_standard"
BODY_TYPE"PLUMBING"
HDL_TAP"TRUE";
"B \NAC \NWC"10;
"S \NAC"
BN"1"49;
%"TAP"
"1","(-5875,4675)","2","mstr_standard","I275";
;
CDS_LIB"mstr_standard"
BODY_TYPE"PLUMBING"
HDL_TAP"TRUE";
"B \NAC \NWC"10;
"S \NAC"
BN"2"48;
%"TAP"
"1","(-5875,4575)","2","mstr_standard","I276";
;
CDS_LIB"mstr_standard"
BODY_TYPE"PLUMBING"
HDL_TAP"TRUE";
"B \NAC \NWC"10;
"S \NAC"
BN"3"47;
%"TAP"
"1","(-5875,4375)","2","mstr_standard","I277";
;
CDS_LIB"mstr_standard"
BODY_TYPE"PLUMBING"
HDL_TAP"TRUE";
"B \NAC \NWC"10;
"S \NAC"
BN"5"44;
%"TAP"
"1","(-5875,4475)","2","mstr_standard","I278";
;
CDS_LIB"mstr_standard"
BODY_TYPE"PLUMBING"
HDL_TAP"TRUE";
"B \NAC \NWC"10;
"S \NAC"
BN"4"45;
%"TAP"
"1","(-5875,4275)","2","mstr_standard","I279";
;
CDS_LIB"mstr_standard"
BODY_TYPE"PLUMBING"
HDL_TAP"TRUE";
"B \NAC \NWC"10;
"S \NAC"
BN"6"43;
%"TAP"
"1","(-5875,4175)","2","mstr_standard","I280";
;
CDS_LIB"mstr_standard"
BODY_TYPE"PLUMBING"
HDL_TAP"TRUE";
"B \NAC \NWC"10;
"S \NAC"
BN"7"42;
%"TAP"
"1","(-5675,4025)","2","mstr_standard","I285";
;
CDS_LIB"mstr_standard"
BODY_TYPE"PLUMBING"
HDL_TAP"TRUE";
"B \NAC \NWC"6;
"S \NAC"
BN"9"41;
%"TAP"
"1","(-5875,4075)","2","mstr_standard","I286";
;
CDS_LIB"mstr_standard"
BODY_TYPE"PLUMBING"
HDL_TAP"TRUE";
"B \NAC \NWC"10;
"S \NAC"
BN"8"26;
%"TAP"
"1","(-5875,3975)","2","mstr_standard","I287";
;
CDS_LIB"mstr_standard"
BODY_TYPE"PLUMBING"
HDL_TAP"TRUE";
"B \NAC \NWC"10;
"S \NAC"
BN"9"25;
%"TAP"
"1","(-5875,3825)","2","mstr_standard","I288";
;
CDS_LIB"mstr_standard"
BODY_TYPE"PLUMBING"
HDL_TAP"TRUE";
"B \NAC \NWC"7;
"S \NAC"
BN"0"40;
%"TAP"
"1","(-5875,3775)","2","mstr_standard","I289";
;
CDS_LIB"mstr_standard"
BODY_TYPE"PLUMBING"
HDL_TAP"TRUE";
"B \NAC \NWC"7;
"S \NAC"
BN"1"38;
%"TAP"
"1","(-5875,3725)","2","mstr_standard","I290";
;
CDS_LIB"mstr_standard"
BODY_TYPE"PLUMBING"
HDL_TAP"TRUE";
"B \NAC \NWC"7;
"S \NAC"
BN"2"36;
%"TAP"
"1","(-5875,3625)","2","mstr_standard","I291";
;
CDS_LIB"mstr_standard"
BODY_TYPE"PLUMBING"
HDL_TAP"TRUE";
"B \NAC \NWC"7;
"S \NAC"
BN"4"32;
%"TAP"
"1","(-5875,3675)","2","mstr_standard","I292";
;
CDS_LIB"mstr_standard"
BODY_TYPE"PLUMBING"
HDL_TAP"TRUE";
"B \NAC \NWC"7;
"S \NAC"
BN"3"34;
%"TAP"
"1","(-5875,3525)","2","mstr_standard","I293";
;
CDS_LIB"mstr_standard"
BODY_TYPE"PLUMBING"
HDL_TAP"TRUE";
"B \NAC \NWC"7;
"S \NAC"
BN"6"28;
%"TAP"
"1","(-5875,3575)","2","mstr_standard","I294";
;
CDS_LIB"mstr_standard"
BODY_TYPE"PLUMBING"
HDL_TAP"TRUE";
"B \NAC \NWC"7;
"S \NAC"
BN"5"30;
%"TAP"
"1","(-5875,3375)","2","mstr_standard","I295";
;
CDS_LIB"mstr_standard"
BODY_TYPE"PLUMBING"
HDL_TAP"TRUE";
"B \NAC \NWC"8;
"S \NAC"
BN"1"37;
%"TAP"
"1","(-5875,3425)","2","mstr_standard","I296";
;
CDS_LIB"mstr_standard"
BODY_TYPE"PLUMBING"
HDL_TAP"TRUE";
"B \NAC \NWC"8;
"S \NAC"
BN"0"39;
%"TAP"
"1","(-5875,3325)","2","mstr_standard","I297";
;
CDS_LIB"mstr_standard"
BODY_TYPE"PLUMBING"
HDL_TAP"TRUE";
"B \NAC \NWC"8;
"S \NAC"
BN"2"35;
%"TAP"
"1","(-5875,3275)","2","mstr_standard","I298";
;
CDS_LIB"mstr_standard"
BODY_TYPE"PLUMBING"
HDL_TAP"TRUE";
"B \NAC \NWC"8;
"S \NAC"
BN"3"33;
%"TAP"
"1","(-5875,3225)","2","mstr_standard","I299";
;
CDS_LIB"mstr_standard"
BODY_TYPE"PLUMBING"
HDL_TAP"TRUE";
"B \NAC \NWC"8;
"S \NAC"
BN"4"31;
%"TAP"
"1","(-5875,3125)","2","mstr_standard","I300";
;
CDS_LIB"mstr_standard"
BODY_TYPE"PLUMBING"
HDL_TAP"TRUE";
"B \NAC \NWC"8;
"S \NAC"
BN"6"27;
%"TAP"
"1","(-5875,3175)","2","mstr_standard","I301";
;
CDS_LIB"mstr_standard"
BODY_TYPE"PLUMBING"
HDL_TAP"TRUE";
"B \NAC \NWC"8;
"S \NAC"
BN"5"29;
%"Q_RES"
"1","(-6800,2125)","0","pure_quanta","I314";
;
LOCATION"R383"
$SEC"1"
CDS_SEC"1"
TOLERANCE"1%"
VALUE"15   "
PART_NUMBER"CS01502FB11"
PACK_TYPE"0402LF"
CDS_LIB"pure_quanta"
WATTAGE"1/16W"
MATERIAL"CHIP";
"B"
$PN"2"13;
"A"
$PN"1"11;
END.
